# BASEBOARD_FAB2 (Tioga Pass) — schematic netlist excerpt (pin names and nets, part order shuffled) for the footprints in the layout excerpt that follows; sources: Cadence DE-HDL packaged netlist, KiCad conversion of Wiwynn_Tioga_Pass_MB.brd

C5D6  CAP_A  22.0UF 4V 20% X6S  pkg 0603V  page 220 : A = PVDDQ_DEF ; B = GND
R2P22  RES  10.0K 1% CHIP  pkg 0402  page 133 : A = P3V3_STBY ; B = FM_CPU1_RC_EN
L7A5  IND-100NH-35-GP  pkg DISCRET-G8  page 220 : S = P12V_STBY ; F = VR_FET_SW_P12V_STBY_PVDDQ_DEF

(kicad_pcb
	(version 20260206)
	(generator "pcbnew")
	(generator_version "10.0")
	(general
		(thickness 1.6)
		(legacy_teardrops no)
	)
	(paper "A4")
	(title_block
		(title "Wiwynn_Tioga_Pass_MB.brd")
		(comment 1 "Tioga Pass / footprints 621-623 of 4770")
	)
	(layers
		(0 "F.Cu" signal "TOP")
		(4 "In1.Cu" signal "L2GND")
		(6 "In2.Cu" signal "L3")
		(8 "In3.Cu" signal "L4GND")
		(10 "In4.Cu" signal "L5")
		(12 "In5.Cu" signal "L6GND")
		(14 "In6.Cu" signal "L7VCC")
		(16 "In7.Cu" signal "L8VCC")
		(18 "In8.Cu" signal "L9GND")
		(20 "In9.Cu" signal "L10")
		(22 "In10.Cu" signal "L11GND")
		(24 "In11.Cu" signal "L12")
		(26 "In12.Cu" signal "L13GND")
		(2 "B.Cu" signal "BOTTOM")
		(9 "F.Adhes" user "F.Adhesive")
		(11 "B.Adhes" user "B.Adhesive")
		(13 "F.Paste" user "Package Geometry/Pastemask Top")
		(15 "B.Paste" user "Package Geometry/Pastemask Bottom")
		(5 "F.SilkS" user "Ref Des/Silkscreen Top")
		(7 "B.SilkS" user "Ref Des/Silkscreen Bottom")
		(1 "F.Mask" user "Board Geometry/Soldermask Top")
		(3 "B.Mask" user "Board Geometry/Soldermask Bottom")
		(17 "Dwgs.User" user "User.Drawings")
		(19 "Cmts.User" user "User.Comments")
		(21 "Eco1.User" user "User.Eco1")
		(23 "Eco2.User" user "User.Eco2")
		(25 "Edge.Cuts" user "Board Geometry/Outline")
		(27 "Margin" user)
		(31 "F.CrtYd" user "Package Geometry/Place Bound Top")
		(29 "B.CrtYd" user "Package Geometry/Place Bound Bottom")
		(35 "F.Fab" user "Ref Des/Assembly Top")
		(33 "B.Fab" user "Ref Des/Assembly Bottom")
	)
	(footprint ""
		(layer "F.Cu")
		(at 408.673046 -107.434634 -90)
		(property "Reference" "R2P22"
			(at -0.8382 -0.849376 270)
			(unlocked yes)
			(layer "F.SilkS")
			(effects
				(font
					(size 0.7874 0.5842)
					(thickness 0.1524)
				)
				(justify left)
			)
		)
		(property "Value" ""
			(at 0 0 270)
			(layer "F.Fab")
			(effects
				(font
					(size 1.27 1.27)
				)
			)
		)
		(duplicate_pad_numbers_are_jumpers no)
		(fp_poly
			(pts
				(xy -0.2794 -0.1016) (xy 0.2794 -0.1016) (xy 0.2794 0.9906) (xy -0.2794 0.9906)
			)
			(stroke
				(width 0)
				(type default)
			)
			(fill no)
			(layer "F.CrtYd")
		)
		(fp_line
			(start -0.2794 0.9906)
			(end 0.2794 0.9906)
			(stroke
				(width 0.1)
				(type default)
			)
			(layer "F.Fab")
		)
		(fp_line
			(start 0.2794 0.9906)
			(end 0.2794 -0.1016)
			(stroke
				(width 0.1)
				(type default)
			)
			(layer "F.Fab")
		)
		(fp_line
			(start -0.2794 -0.1016)
			(end -0.2794 0.9906)
			(stroke
				(width 0.1)
				(type default)
			)
			(layer "F.Fab")
		)
		(fp_line
			(start 0.2794 -0.1016)
			(end -0.2794 -0.1016)
			(stroke
				(width 0.1)
				(type default)
			)
			(layer "F.Fab")
		)
		(pad "1" smd rect
			(at 0 0 270)
			(size 0.508 0.508)
			(layers "F.Cu" "F.Mask" "F.Paste")
			(net "P3V3_STBY")
		)
		(pad "2" smd rect
			(at 0 0.889 270)
			(size 0.508 0.508)
			(layers "F.Cu" "F.Mask" "F.Paste")
			(net "FM_CPU1_RC_EN")
		)
		(zone
			(layer "F.Cu")
			(hatch none 0.5)
			(connect_pads
				(clearance 0)
			)
			(min_thickness 0.25)
			(keepout
				(tracks not_allowed)
				(vias allowed)
				(pads allowed)
				(copperpour not_allowed)
				(footprints allowed)
			)
			(placement
				(enabled no)
				(sheetname "")
			)
			(fill
				(thermal_gap 0.5)
				(thermal_bridge_width 0.5)
				(island_removal_mode 0)
			)
			(polygon
				(pts
					(xy 408.038046 -107.688634) (xy 408.038046 -107.180634) (xy 408.419046 -107.180634) (xy 408.419046 -107.688634)
				)
			)
		)
		(zone
			(layer "F.Cu")
			(hatch none 0.5)
			(connect_pads
				(clearance 0)
			)
			(min_thickness 0.25)
			(keepout
				(tracks allowed)
				(vias not_allowed)
				(pads allowed)
				(copperpour not_allowed)
				(footprints allowed)
			)
			(placement
				(enabled no)
				(sheetname "")
			)
			(fill
				(thermal_gap 0.5)
				(thermal_bridge_width 0.5)
				(island_removal_mode 0)
			)
			(polygon
				(pts
					(xy 408.419046 -107.688634) (xy 408.419046 -107.180634) (xy 408.038046 -107.180634) (xy 408.038046 -107.688634)
				)
			)
		)
	)
	(footprint ""
		(layer "F.Cu")
		(at 264.7696 -84.7598)
		(property "Reference" "C5D6"
			(at 0 0 0)
			(layer "F.SilkS")
			(hide yes)
			(effects
				(font
					(size 1.27 1.27)
				)
			)
		)
		(property "Value" ""
			(at 0 0 0)
			(layer "F.Fab")
			(effects
				(font
					(size 1.27 1.27)
				)
			)
		)
		(duplicate_pad_numbers_are_jumpers no)
		(fp_poly
			(pts
				(xy -0.4953 -0.2032) (xy 0.4953 -0.2032) (xy 0.4953 1.6002) (xy -0.4953 1.6002)
			)
			(stroke
				(width 0)
				(type default)
			)
			(fill no)
			(layer "F.CrtYd")
		)
		(fp_line
			(start -0.4953 -0.2032)
			(end 0.4953 -0.2032)
			(stroke
				(width 0.1)
				(type default)
			)
			(layer "F.Fab")
		)
		(fp_line
			(start -0.4953 1.6002)
			(end -0.4953 -0.2032)
			(stroke
				(width 0.1)
				(type default)
			)
			(layer "F.Fab")
		)
		(fp_line
			(start 0.4953 -0.2032)
			(end 0.4953 1.6002)
			(stroke
				(width 0.1)
				(type default)
			)
			(layer "F.Fab")
		)
		(fp_line
			(start 0.4953 1.6002)
			(end -0.4953 1.6002)
			(stroke
				(width 0.1)
				(type default)
			)
			(layer "F.Fab")
		)
		(pad "1" smd rect
			(at 0 0)
			(size 0.762 0.889)
			(layers "F.Cu" "F.Mask" "F.Paste")
			(net "PVDDQ_DEF")
		)
		(pad "2" smd rect
			(at 0 1.397)
			(size 0.762 0.889)
			(layers "F.Cu" "F.Mask" "F.Paste")
			(net "GND")
		)
		(zone
			(layer "F.Cu")
			(hatch none 0.5)
			(connect_pads
				(clearance 0)
			)
			(min_thickness 0.25)
			(keepout
				(tracks not_allowed)
				(vias allowed)
				(pads allowed)
				(copperpour not_allowed)
				(footprints allowed)
			)
			(placement
				(enabled no)
				(sheetname "")
			)
			(fill
				(thermal_gap 0.5)
				(thermal_bridge_width 0.5)
				(island_removal_mode 0)
			)
			(polygon
				(pts
					(xy 264.3886 -84.3153) (xy 265.1506 -84.3153) (xy 265.1506 -83.8073) (xy 264.3886 -83.8073)
				)
			)
		)
	)
	(footprint ""
		(layer "F.Cu")
		(at 362.593382 -147.15871 180)
		(property "Reference" "L7A5"
			(at 0 0 180)
			(layer "F.SilkS")
			(hide yes)
			(effects
				(font
					(size 1.27 1.27)
				)
			)
		)
		(property "Value" "*"
			(at -3.5941 0.3429 180)
			(unlocked yes)
			(layer "F.Fab")
			(hide yes)
			(effects
				(font
					(size 1.27 1.016)
					(thickness 0.1524)
				)
			)
		)
		(property "Device Type" "IND-100NH-35-GP_DISCRET-G8-INDA"
			(at -3.5941 -1.1811 180)
			(unlocked yes)
			(layer "F.Fab")
			(hide yes)
			(effects
				(font
					(size 1.27 1.016)
					(thickness 0.1524)
				)
			)
		)
		(duplicate_pad_numbers_are_jumpers no)
		(fp_line
			(start 2.2479 2.794)
			(end -2.2479 2.794)
			(stroke
				(width 0.1524)
				(type default)
			)
			(layer "F.SilkS")
		)
		(fp_line
			(start 2.2479 -2.794)
			(end 2.2479 2.794)
			(stroke
				(width 0.1524)
				(type default)
			)
			(layer "F.SilkS")
		)
		(fp_line
			(start -2.2479 2.794)
			(end -2.2479 -2.794)
			(stroke
				(width 0.1524)
				(type default)
			)
			(layer "F.SilkS")
		)
		(fp_line
			(start -2.2479 -2.794)
			(end 2.2479 -2.794)
			(stroke
				(width 0.1524)
				(type default)
			)
			(layer "F.SilkS")
		)
		(fp_rect
			(start -1.9939 1.9939)
			(end 1.9939 -1.9939)
			(stroke
				(width 0)
				(type default)
			)
			(fill no)
			(layer "F.CrtYd")
		)
		(fp_poly
			(pts
				(xy -2.5019 2.8702) (xy -2.5019 1.9939) (xy 1.9939 1.9939) (xy 1.9939 -1.9939) (xy -1.9939 -1.9939)
				(xy -1.9939 1.9812) (xy -2.5019 1.9812) (xy -2.5019 -2.8702) (xy 2.5019 -2.8702) (xy 2.5019 2.8702)
			)
			(stroke
				(width 0)
				(type default)
			)
			(fill no)
			(layer "F.CrtYd")
		)
		(fp_rect
			(start -2.5019 2.8702)
			(end 2.5019 -2.8702)
			(stroke
				(width 0)
				(type default)
			)
			(fill no)
			(layer "F.Fab")
		)
		(pad "1" smd rect
			(at 0 -1.745996 180)
			(size 1.5494 1.6002)
			(layers "F.Cu" "F.Mask" "F.Paste")
			(net "P12V_STBY")
		)
		(pad "2" smd rect
			(at 0 1.745996 180)
			(size 1.5494 1.6002)
			(layers "F.Cu" "F.Mask" "F.Paste")
			(net "VR_FET_SW_P12V_STBY_PVDDQ_DEF")
		)
	)
)
